(kicad_pcb
	(version 20260206)
	(generator "pcbnew")
	(generator_version "10.0")
	(general
		(thickness 1.6)
		(legacy_teardrops no)
	)
	(paper "A4")
	(title_block
		(title "01162023_DA0F0TEBIF0_F0T_Expander_BD_F_brd_V02_OCP.brd")
		(comment 1 "Grand Teton / footprints 6964-6970 of 9728")
	)
	(layers
		(0 "F.Cu" signal "TOP")
		(4 "In1.Cu" signal "GND")
		(6 "In2.Cu" signal "VCC")
		(8 "In3.Cu" signal "VCC1")
		(10 "In4.Cu" signal "GND1")
		(12 "In5.Cu" signal "IN1")
		(14 "In6.Cu" signal "GND2")
		(16 "In7.Cu" signal "IN2")
		(18 "In8.Cu" signal "GND3")
		(20 "In9.Cu" signal "IN3")
		(22 "In10.Cu" signal "GND4")
		(24 "In11.Cu" signal "IN4")
		(26 "In12.Cu" signal "GND5")
		(28 "In13.Cu" signal "IN5")
		(30 "In14.Cu" signal "GND6")
		(32 "In15.Cu" signal "IN6")
		(34 "In16.Cu" signal "GND7")
		(2 "B.Cu" signal "BOTTOM")
		(9 "F.Adhes" user "F.Adhesive")
		(11 "B.Adhes" user "B.Adhesive")
		(13 "F.Paste" user "Package Geometry/Pastemask Top")
		(15 "B.Paste" user "Package Geometry/Pastemask Bottom")
		(5 "F.SilkS" user "Ref Des/Silkscreen Top")
		(7 "B.SilkS" user "Ref Des/Silkscreen Bottom")
		(1 "F.Mask" user "Board Geometry/Soldermask Top")
		(3 "B.Mask" user "Board Geometry/Soldermask Bottom")
		(17 "Dwgs.User" user "User.Drawings")
		(19 "Cmts.User" user "User.Comments")
		(21 "Eco1.User" user "User.Eco1")
		(23 "Eco2.User" user "User.Eco2")
		(25 "Edge.Cuts" user "Board Geometry/Outline")
		(27 "Margin" user)
		(31 "F.CrtYd" user "Package Geometry/Place Bound Top")
		(29 "B.CrtYd" user "Package Geometry/Place Bound Bottom")
		(35 "F.Fab" user "Ref Des/Assembly Top")
		(33 "B.Fab" user "Ref Des/Assembly Bottom")
	)
	(footprint ""
		(layer "F.Cu")
		(at 119.061484 -284.834838 90)
		(property "Reference" "PC92"
			(at 0 0 90)
			(layer "F.SilkS")
			(hide yes)
			(effects
				(font
					(size 1.27 1.27)
				)
			)
		)
		(property "Value" ""
			(at 0 0 90)
			(layer "F.Fab")
			(effects
				(font
					(size 1.27 1.27)
				)
			)
		)
		(duplicate_pad_numbers_are_jumpers no)
		(fp_line
			(start 0.7874 -0.4064)
			(end 0.7874 0.4064)
			(stroke
				(width 0.1524)
				(type default)
			)
			(layer "F.SilkS")
		)
		(fp_line
			(start -0.7874 -0.4064)
			(end 0.7874 -0.4064)
			(stroke
				(width 0.1524)
				(type default)
			)
			(layer "F.SilkS")
		)
		(fp_line
			(start 0.7874 0.4064)
			(end -0.7874 0.4064)
			(stroke
				(width 0.1524)
				(type default)
			)
			(layer "F.SilkS")
		)
		(fp_line
			(start -0.7874 0.4064)
			(end -0.7874 -0.4064)
			(stroke
				(width 0.1524)
				(type default)
			)
			(layer "F.SilkS")
		)
		(fp_line
			(start -0.12065 -0.305054)
			(end -0.12065 -0.2794)
			(stroke
				(width 0.1)
				(type default)
			)
			(layer "F.Fab")
		)
		(fp_line
			(start -0.67945 -0.305054)
			(end -0.12065 -0.305054)
			(stroke
				(width 0.1)
				(type default)
			)
			(layer "F.Fab")
		)
		(fp_line
			(start 0.67945 -0.3048)
			(end 0.67945 0.3048)
			(stroke
				(width 0.1)
				(type default)
			)
			(layer "F.Fab")
		)
		(fp_line
			(start 0.12065 -0.3048)
			(end 0.67945 -0.3048)
			(stroke
				(width 0.1)
				(type default)
			)
			(layer "F.Fab")
		)
		(fp_line
			(start 0.12065 -0.2794)
			(end 0.12065 -0.3048)
			(stroke
				(width 0.1)
				(type default)
			)
			(layer "F.Fab")
		)
		(fp_line
			(start -0.12065 -0.2794)
			(end 0.12065 -0.2794)
			(stroke
				(width 0.1)
				(type default)
			)
			(layer "F.Fab")
		)
		(fp_line
			(start 0.120396 0.2794)
			(end -0.12065 0.2794)
			(stroke
				(width 0.1)
				(type default)
			)
			(layer "F.Fab")
		)
		(fp_line
			(start -0.12065 0.2794)
			(end -0.12065 0.3048)
			(stroke
				(width 0.1)
				(type default)
			)
			(layer "F.Fab")
		)
		(fp_line
			(start 0.67945 0.3048)
			(end 0.120396 0.3048)
			(stroke
				(width 0.1)
				(type default)
			)
			(layer "F.Fab")
		)
		(fp_line
			(start 0.120396 0.3048)
			(end 0.120396 0.2794)
			(stroke
				(width 0.1)
				(type default)
			)
			(layer "F.Fab")
		)
		(fp_line
			(start -0.12065 0.3048)
			(end -0.67945 0.3048)
			(stroke
				(width 0.1)
				(type default)
			)
			(layer "F.Fab")
		)
		(fp_line
			(start -0.67945 0.3048)
			(end -0.67945 -0.305054)
			(stroke
				(width 0.1)
				(type default)
			)
			(layer "F.Fab")
		)
		(pad "1" smd circle
			(at -0.40005 0 90)
			(size 0 0)
			(layers "F.Cu" "F.Mask" "F.Paste")
			(net "SW_P12V_P0V8_PEX1_FLT")
		)
		(pad "2" smd circle
			(at 0.40005 0 90)
			(size 0 0)
			(layers "F.Cu" "F.Mask" "F.Paste")
			(net "GND")
		)
	)
	(footprint ""
		(layer "F.Cu")
		(at 452.543672 -44.87291)
		(property "Reference" "R672"
			(at 0 0 0)
			(layer "F.SilkS")
			(hide yes)
			(effects
				(font
					(size 1.27 1.27)
				)
			)
		)
		(property "Value" ""
			(at 0 0 0)
			(layer "F.Fab")
			(effects
				(font
					(size 1.27 1.27)
				)
			)
		)
		(duplicate_pad_numbers_are_jumpers no)
		(fp_line
			(start -0.7874 -0.4064)
			(end 0.7874 -0.4064)
			(stroke
				(width 0.1524)
				(type default)
			)
			(layer "F.SilkS")
		)
		(fp_line
			(start -0.7874 0.4064)
			(end -0.7874 -0.4064)
			(stroke
				(width 0.1524)
				(type default)
			)
			(layer "F.SilkS")
		)
		(fp_line
			(start 0.7874 -0.4064)
			(end 0.7874 0.4064)
			(stroke
				(width 0.1524)
				(type default)
			)
			(layer "F.SilkS")
		)
		(fp_line
			(start 0.7874 0.4064)
			(end -0.7874 0.4064)
			(stroke
				(width 0.1524)
				(type default)
			)
			(layer "F.SilkS")
		)
		(fp_line
			(start -0.67945 -0.305054)
			(end -0.12065 -0.305054)
			(stroke
				(width 0.1)
				(type default)
			)
			(layer "F.Fab")
		)
		(fp_line
			(start -0.67945 0.3048)
			(end -0.67945 -0.305054)
			(stroke
				(width 0.1)
				(type default)
			)
			(layer "F.Fab")
		)
		(fp_line
			(start -0.12065 -0.305054)
			(end -0.12065 -0.2794)
			(stroke
				(width 0.1)
				(type default)
			)
			(layer "F.Fab")
		)
		(fp_line
			(start -0.12065 -0.2794)
			(end 0.12065 -0.2794)
			(stroke
				(width 0.1)
				(type default)
			)
			(layer "F.Fab")
		)
		(fp_line
			(start -0.12065 0.2794)
			(end -0.12065 0.3048)
			(stroke
				(width 0.1)
				(type default)
			)
			(layer "F.Fab")
		)
		(fp_line
			(start -0.12065 0.3048)
			(end -0.67945 0.3048)
			(stroke
				(width 0.1)
				(type default)
			)
			(layer "F.Fab")
		)
		(fp_line
			(start 0.120396 0.2794)
			(end -0.12065 0.2794)
			(stroke
				(width 0.1)
				(type default)
			)
			(layer "F.Fab")
		)
		(fp_line
			(start 0.120396 0.3048)
			(end 0.120396 0.2794)
			(stroke
				(width 0.1)
				(type default)
			)
			(layer "F.Fab")
		)
		(fp_line
			(start 0.12065 -0.3048)
			(end 0.67945 -0.3048)
			(stroke
				(width 0.1)
				(type default)
			)
			(layer "F.Fab")
		)
		(fp_line
			(start 0.12065 -0.2794)
			(end 0.12065 -0.3048)
			(stroke
				(width 0.1)
				(type default)
			)
			(layer "F.Fab")
		)
		(fp_line
			(start 0.67945 -0.3048)
			(end 0.67945 0.3048)
			(stroke
				(width 0.1)
				(type default)
			)
			(layer "F.Fab")
		)
		(fp_line
			(start 0.67945 0.3048)
			(end 0.120396 0.3048)
			(stroke
				(width 0.1)
				(type default)
			)
			(layer "F.Fab")
		)
		(pad "1" smd circle
			(at -0.40005 0)
			(size 0 0)
			(layers "F.Cu" "F.Mask" "F.Paste")
			(net "SSD15_ADC_A0")
		)
		(pad "2" smd circle
			(at 0.40005 0)
			(size 0 0)
			(layers "F.Cu" "F.Mask" "F.Paste")
			(net "P3V3_AUX")
		)
	)
	(footprint ""
		(layer "F.Cu")
		(at 268.512036 -137.2489 -90)
		(property "Reference" "C915"
			(at 0 0 270)
			(layer "F.SilkS")
			(hide yes)
			(effects
				(font
					(size 1.27 1.27)
				)
			)
		)
		(property "Value" ""
			(at 0 0 270)
			(layer "F.Fab")
			(effects
				(font
					(size 1.27 1.27)
				)
			)
		)
		(duplicate_pad_numbers_are_jumpers no)
		(fp_line
			(start -0.7874 0.4064)
			(end -0.7874 -0.4064)
			(stroke
				(width 0.1524)
				(type default)
			)
			(layer "F.SilkS")
		)
		(fp_line
			(start 0.7874 0.4064)
			(end -0.7874 0.4064)
			(stroke
				(width 0.1524)
				(type default)
			)
			(layer "F.SilkS")
		)
		(fp_line
			(start -0.7874 -0.4064)
			(end 0.7874 -0.4064)
			(stroke
				(width 0.1524)
				(type default)
			)
			(layer "F.SilkS")
		)
		(fp_line
			(start 0.7874 -0.4064)
			(end 0.7874 0.4064)
			(stroke
				(width 0.1524)
				(type default)
			)
			(layer "F.SilkS")
		)
		(fp_line
			(start -0.67945 0.3048)
			(end -0.67945 -0.305054)
			(stroke
				(width 0.1)
				(type default)
			)
			(layer "F.Fab")
		)
		(fp_line
			(start -0.12065 0.3048)
			(end -0.67945 0.3048)
			(stroke
				(width 0.1)
				(type default)
			)
			(layer "F.Fab")
		)
		(fp_line
			(start 0.120396 0.3048)
			(end 0.120396 0.2794)
			(stroke
				(width 0.1)
				(type default)
			)
			(layer "F.Fab")
		)
		(fp_line
			(start 0.67945 0.3048)
			(end 0.120396 0.3048)
			(stroke
				(width 0.1)
				(type default)
			)
			(layer "F.Fab")
		)
		(fp_line
			(start -0.12065 0.2794)
			(end -0.12065 0.3048)
			(stroke
				(width 0.1)
				(type default)
			)
			(layer "F.Fab")
		)
		(fp_line
			(start 0.120396 0.2794)
			(end -0.12065 0.2794)
			(stroke
				(width 0.1)
				(type default)
			)
			(layer "F.Fab")
		)
		(fp_line
			(start -0.12065 -0.2794)
			(end 0.12065 -0.2794)
			(stroke
				(width 0.1)
				(type default)
			)
			(layer "F.Fab")
		)
		(fp_line
			(start 0.12065 -0.2794)
			(end 0.12065 -0.3048)
			(stroke
				(width 0.1)
				(type default)
			)
			(layer "F.Fab")
		)
		(fp_line
			(start 0.12065 -0.3048)
			(end 0.67945 -0.3048)
			(stroke
				(width 0.1)
				(type default)
			)
			(layer "F.Fab")
		)
		(fp_line
			(start 0.67945 -0.3048)
			(end 0.67945 0.3048)
			(stroke
				(width 0.1)
				(type default)
			)
			(layer "F.Fab")
		)
		(fp_line
			(start -0.67945 -0.305054)
			(end -0.12065 -0.305054)
			(stroke
				(width 0.1)
				(type default)
			)
			(layer "F.Fab")
		)
		(fp_line
			(start -0.12065 -0.305054)
			(end -0.12065 -0.2794)
			(stroke
				(width 0.1)
				(type default)
			)
			(layer "F.Fab")
		)
		(pad "1" smd circle
			(at -0.40005 0 270)
			(size 0 0)
			(layers "F.Cu" "F.Mask" "F.Paste")
			(net "P3V3_NIC4")
		)
		(pad "2" smd circle
			(at 0.40005 0 270)
			(size 0 0)
			(layers "F.Cu" "F.Mask" "F.Paste")
			(net "GND")
		)
	)
	(footprint ""
		(layer "F.Cu")
		(at 327.992232 -32.739584 180)
		(property "Reference" "C513"
			(at 0 0 180)
			(layer "F.SilkS")
			(hide yes)
			(effects
				(font
					(size 1.27 1.27)
				)
			)
		)
		(property "Value" ""
			(at 0 0 180)
			(layer "F.Fab")
			(effects
				(font
					(size 1.27 1.27)
				)
			)
		)
		(duplicate_pad_numbers_are_jumpers no)
		(fp_line
			(start 0.299974 0.150114)
			(end -0.299974 0.150114)
			(stroke
				(width 0.1)
				(type default)
			)
			(layer "F.Fab")
		)
		(fp_line
			(start 0.299974 -0.150114)
			(end 0.299974 0.150114)
			(stroke
				(width 0.1)
				(type default)
			)
			(layer "F.Fab")
		)
		(fp_line
			(start -0.299974 0.150114)
			(end -0.299974 -0.150114)
			(stroke
				(width 0.1)
				(type default)
			)
			(layer "F.Fab")
		)
		(fp_line
			(start -0.299974 -0.150114)
			(end 0.299974 -0.150114)
			(stroke
				(width 0.1)
				(type default)
			)
			(layer "F.Fab")
		)
		(pad "1" smd rect
			(at -0.2667 0 180)
			(size 0.3048 0.381)
			(layers "F.Cu" "F.Mask" "F.Paste")
			(net "P5E_PEX2_STN2_TX_DP<34>")
		)
		(pad "2" smd rect
			(at 0.2667 0 180)
			(size 0.3048 0.381)
			(layers "F.Cu" "F.Mask" "F.Paste")
			(net "P5E_PEX2_STN2_TX_C_DP<34>")
		)
	)
	(footprint ""
		(layer "F.Cu")
		(at 258.54533 -197.097396)
		(property "Reference" "R4900"
			(at 0 0 0)
			(layer "F.SilkS")
			(hide yes)
			(effects
				(font
					(size 1.27 1.27)
				)
			)
		)
		(property "Value" ""
			(at 0 0 0)
			(layer "F.Fab")
			(effects
				(font
					(size 1.27 1.27)
				)
			)
		)
		(duplicate_pad_numbers_are_jumpers no)
		(fp_line
			(start -0.7874 -0.4064)
			(end 0.7874 -0.4064)
			(stroke
				(width 0.1524)
				(type default)
			)
			(layer "F.SilkS")
		)
		(fp_line
			(start -0.7874 0.4064)
			(end -0.7874 -0.4064)
			(stroke
				(width 0.1524)
				(type default)
			)
			(layer "F.SilkS")
		)
		(fp_line
			(start 0.7874 -0.4064)
			(end 0.7874 0.4064)
			(stroke
				(width 0.1524)
				(type default)
			)
			(layer "F.SilkS")
		)
		(fp_line
			(start 0.7874 0.4064)
			(end -0.7874 0.4064)
			(stroke
				(width 0.1524)
				(type default)
			)
			(layer "F.SilkS")
		)
		(fp_line
			(start -0.67945 -0.305054)
			(end -0.12065 -0.305054)
			(stroke
				(width 0.1)
				(type default)
			)
			(layer "F.Fab")
		)
		(fp_line
			(start -0.67945 0.3048)
			(end -0.67945 -0.305054)
			(stroke
				(width 0.1)
				(type default)
			)
			(layer "F.Fab")
		)
		(fp_line
			(start -0.12065 -0.305054)
			(end -0.12065 -0.2794)
			(stroke
				(width 0.1)
				(type default)
			)
			(layer "F.Fab")
		)
		(fp_line
			(start -0.12065 -0.2794)
			(end 0.12065 -0.2794)
			(stroke
				(width 0.1)
				(type default)
			)
			(layer "F.Fab")
		)
		(fp_line
			(start -0.12065 0.2794)
			(end -0.12065 0.3048)
			(stroke
				(width 0.1)
				(type default)
			)
			(layer "F.Fab")
		)
		(fp_line
			(start -0.12065 0.3048)
			(end -0.67945 0.3048)
			(stroke
				(width 0.1)
				(type default)
			)
			(layer "F.Fab")
		)
		(fp_line
			(start 0.120396 0.2794)
			(end -0.12065 0.2794)
			(stroke
				(width 0.1)
				(type default)
			)
			(layer "F.Fab")
		)
		(fp_line
			(start 0.120396 0.3048)
			(end 0.120396 0.2794)
			(stroke
				(width 0.1)
				(type default)
			)
			(layer "F.Fab")
		)
		(fp_line
			(start 0.12065 -0.3048)
			(end 0.67945 -0.3048)
			(stroke
				(width 0.1)
				(type default)
			)
			(layer "F.Fab")
		)
		(fp_line
			(start 0.12065 -0.2794)
			(end 0.12065 -0.3048)
			(stroke
				(width 0.1)
				(type default)
			)
			(layer "F.Fab")
		)
		(fp_line
			(start 0.67945 -0.3048)
			(end 0.67945 0.3048)
			(stroke
				(width 0.1)
				(type default)
			)
			(layer "F.Fab")
		)
		(fp_line
			(start 0.67945 0.3048)
			(end 0.120396 0.3048)
			(stroke
				(width 0.1)
				(type default)
			)
			(layer "F.Fab")
		)
		(pad "1" smd circle
			(at -0.40005 0)
			(size 0 0)
			(layers "F.Cu" "F.Mask" "F.Paste")
			(net "JTAG_FPGA_TMS")
		)
		(pad "2" smd circle
			(at 0.40005 0)
			(size 0 0)
			(layers "F.Cu" "F.Mask" "F.Paste")
			(net "JTAG_CONN_TMS")
		)
	)
	(footprint ""
		(layer "F.Cu")
		(at 44.722542 -44.341542 90)
		(property "Reference" "R525"
			(at 0 0 90)
			(layer "F.SilkS")
			(hide yes)
			(effects
				(font
					(size 1.27 1.27)
				)
			)
		)
		(property "Value" ""
			(at 0 0 90)
			(layer "F.Fab")
			(effects
				(font
					(size 1.27 1.27)
				)
			)
		)
		(duplicate_pad_numbers_are_jumpers no)
		(fp_line
			(start 0.7874 -0.4064)
			(end 0.7874 0.4064)
			(stroke
				(width 0.1524)
				(type default)
			)
			(layer "F.SilkS")
		)
		(fp_line
			(start -0.7874 -0.4064)
			(end 0.7874 -0.4064)
			(stroke
				(width 0.1524)
				(type default)
			)
			(layer "F.SilkS")
		)
		(fp_line
			(start 0.7874 0.4064)
			(end -0.7874 0.4064)
			(stroke
				(width 0.1524)
				(type default)
			)
			(layer "F.SilkS")
		)
		(fp_line
			(start -0.7874 0.4064)
			(end -0.7874 -0.4064)
			(stroke
				(width 0.1524)
				(type default)
			)
			(layer "F.SilkS")
		)
		(fp_line
			(start -0.12065 -0.305054)
			(end -0.12065 -0.2794)
			(stroke
				(width 0.1)
				(type default)
			)
			(layer "F.Fab")
		)
		(fp_line
			(start -0.67945 -0.305054)
			(end -0.12065 -0.305054)
			(stroke
				(width 0.1)
				(type default)
			)
			(layer "F.Fab")
		)
		(fp_line
			(start 0.67945 -0.3048)
			(end 0.67945 0.3048)
			(stroke
				(width 0.1)
				(type default)
			)
			(layer "F.Fab")
		)
		(fp_line
			(start 0.12065 -0.3048)
			(end 0.67945 -0.3048)
			(stroke
				(width 0.1)
				(type default)
			)
			(layer "F.Fab")
		)
		(fp_line
			(start 0.12065 -0.2794)
			(end 0.12065 -0.3048)
			(stroke
				(width 0.1)
				(type default)
			)
			(layer "F.Fab")
		)
		(fp_line
			(start -0.12065 -0.2794)
			(end 0.12065 -0.2794)
			(stroke
				(width 0.1)
				(type default)
			)
			(layer "F.Fab")
		)
		(fp_line
			(start 0.120396 0.2794)
			(end -0.12065 0.2794)
			(stroke
				(width 0.1)
				(type default)
			)
			(layer "F.Fab")
		)
		(fp_line
			(start -0.12065 0.2794)
			(end -0.12065 0.3048)
			(stroke
				(width 0.1)
				(type default)
			)
			(layer "F.Fab")
		)
		(fp_line
			(start 0.67945 0.3048)
			(end 0.120396 0.3048)
			(stroke
				(width 0.1)
				(type default)
			)
			(layer "F.Fab")
		)
		(fp_line
			(start 0.120396 0.3048)
			(end 0.120396 0.2794)
			(stroke
				(width 0.1)
				(type default)
			)
			(layer "F.Fab")
		)
		(fp_line
			(start -0.12065 0.3048)
			(end -0.67945 0.3048)
			(stroke
				(width 0.1)
				(type default)
			)
			(layer "F.Fab")
		)
		(fp_line
			(start -0.67945 0.3048)
			(end -0.67945 -0.305054)
			(stroke
				(width 0.1)
				(type default)
			)
			(layer "F.Fab")
		)
		(pad "1" smd circle
			(at -0.40005 0 90)
			(size 0 0)
			(layers "F.Cu" "F.Mask" "F.Paste")
			(net "P12V_SSD1")
		)
		(pad "2" smd circle
			(at 0.40005 0 90)
			(size 0 0)
			(layers "F.Cu" "F.Mask" "F.Paste")
			(net "P12V_SSD1_VIN_N")
		)
	)
	(footprint ""
		(layer "F.Cu")
		(at 174.80915 -27.04973 180)
		(property "Reference" "C2769"
			(at 0 0 180)
			(layer "F.SilkS")
			(hide yes)
			(effects
				(font
					(size 1.27 1.27)
				)
			)
		)
		(property "Value" ""
			(at 0 0 180)
			(layer "F.Fab")
			(effects
				(font
					(size 1.27 1.27)
				)
			)
		)
		(duplicate_pad_numbers_are_jumpers no)
		(fp_line
			(start 0.7874 0.4064)
			(end -0.7874 0.4064)
			(stroke
				(width 0.1524)
				(type default)
			)
			(layer "F.SilkS")
		)
		(fp_line
			(start 0.7874 -0.4064)
			(end 0.7874 0.4064)
			(stroke
				(width 0.1524)
				(type default)
			)
			(layer "F.SilkS")
		)
		(fp_line
			(start -0.7874 0.4064)
			(end -0.7874 -0.4064)
			(stroke
				(width 0.1524)
				(type default)
			)
			(layer "F.SilkS")
		)
		(fp_line
			(start -0.7874 -0.4064)
			(end 0.7874 -0.4064)
			(stroke
				(width 0.1524)
				(type default)
			)
			(layer "F.SilkS")
		)
		(fp_line
			(start 0.67945 0.3048)
			(end 0.120396 0.3048)
			(stroke
				(width 0.1)
				(type default)
			)
			(layer "F.Fab")
		)
		(fp_line
			(start 0.67945 -0.3048)
			(end 0.67945 0.3048)
			(stroke
				(width 0.1)
				(type default)
			)
			(layer "F.Fab")
		)
		(fp_line
			(start 0.12065 -0.2794)
			(end 0.12065 -0.3048)
			(stroke
				(width 0.1)
				(type default)
			)
			(layer "F.Fab")
		)
		(fp_line
			(start 0.12065 -0.3048)
			(end 0.67945 -0.3048)
			(stroke
				(width 0.1)
				(type default)
			)
			(layer "F.Fab")
		)
		(fp_line
			(start 0.120396 0.3048)
			(end 0.120396 0.2794)
			(stroke
				(width 0.1)
				(type default)
			)
			(layer "F.Fab")
		)
		(fp_line
			(start 0.120396 0.2794)
			(end -0.12065 0.2794)
			(stroke
				(width 0.1)
				(type default)
			)
			(layer "F.Fab")
		)
		(fp_line
			(start -0.12065 0.3048)
			(end -0.67945 0.3048)
			(stroke
				(width 0.1)
				(type default)
			)
			(layer "F.Fab")
		)
		(fp_line
			(start -0.12065 0.2794)
			(end -0.12065 0.3048)
			(stroke
				(width 0.1)
				(type default)
			)
			(layer "F.Fab")
		)
		(fp_line
			(start -0.12065 -0.2794)
			(end 0.12065 -0.2794)
			(stroke
				(width 0.1)
				(type default)
			)
			(layer "F.Fab")
		)
		(fp_line
			(start -0.12065 -0.305054)
			(end -0.12065 -0.2794)
			(stroke
				(width 0.1)
				(type default)
			)
			(layer "F.Fab")
		)
		(fp_line
			(start -0.67945 0.3048)
			(end -0.67945 -0.305054)
			(stroke
				(width 0.1)
				(type default)
			)
			(layer "F.Fab")
		)
		(fp_line
			(start -0.67945 -0.305054)
			(end -0.12065 -0.305054)
			(stroke
				(width 0.1)
				(type default)
			)
			(layer "F.Fab")
		)
		(pad "1" smd circle
			(at -0.40005 0 180)
			(size 0 0)
			(layers "F.Cu" "F.Mask" "F.Paste")
			(net "PRSNT_SSD6_R_N")
		)
		(pad "2" smd circle
			(at 0.40005 0 180)
			(size 0 0)
			(layers "F.Cu" "F.Mask" "F.Paste")
			(net "GND")
		)
	)
)
